# T6G (Grand Teton) — schematic netlist excerpt (pin names and nets, part order shuffled) for the footprints in the layout excerpt that follows; sources: Cadence DE-HDL packaged netlist, KiCad conversion of 04192023_DAF0TMB3IC0_F0TG_MB_C_brd_V02_OCP.brd

U16  M24M02DRMN6TP  M24M02-DRMN6TP IC  pkg SOIC8XH  page 300
  DU1  = NC
  DU2  = NC
  E2  = U16_E2
  VSS  = GND
  SDA  = SMB_RT_CPU0_P2_ROM_SDA
  SCL  = SMB_RT_CPU0_P2_ROM_SCL
  WC_N  = GND
  VCC  = P1V8_CPU0_RT_1D

R8071  Q_RES  0 5% CHIP  pkg 0402LF  page 200 : A = SMB_SCM_2_R5_SCL ; B = SMB_CLK_PVDDCR_CPU1_P0_R

(kicad_pcb
	(version 20260206)
	(generator "pcbnew")
	(generator_version "10.0")
	(general
		(thickness 1.6)
		(legacy_teardrops no)
	)
	(paper "A4")
	(title_block
		(title "04192023_DAF0TMB3IC0_F0TG_MB_C_brd_V02_OCP.brd")
		(comment 1 "Grand Teton / footprints 3831-3832 of 8354")
	)
	(layers
		(0 "F.Cu" signal "TOP")
		(4 "In1.Cu" signal "GND")
		(6 "In2.Cu" signal "IN1")
		(8 "In3.Cu" signal "GND1")
		(10 "In4.Cu" signal "IN2")
		(12 "In5.Cu" signal "GND2")
		(14 "In6.Cu" signal "IN3")
		(16 "In7.Cu" signal "GND3")
		(18 "In8.Cu" signal "VCC")
		(20 "In9.Cu" signal "VCC1")
		(22 "In10.Cu" signal "GND4")
		(24 "In11.Cu" signal "IN4")
		(26 "In12.Cu" signal "GND5")
		(28 "In13.Cu" signal "IN5")
		(30 "In14.Cu" signal "GND6")
		(32 "In15.Cu" signal "IN6")
		(34 "In16.Cu" signal "GND7")
		(2 "B.Cu" signal "BOTTOM")
		(9 "F.Adhes" user "F.Adhesive")
		(11 "B.Adhes" user "B.Adhesive")
		(13 "F.Paste" user "Package Geometry/Pastemask Top")
		(15 "B.Paste" user "Package Geometry/Pastemask Bottom")
		(5 "F.SilkS" user "Ref Des/Silkscreen Top")
		(7 "B.SilkS" user "Ref Des/Silkscreen Bottom")
		(1 "F.Mask" user "Board Geometry/Soldermask Top")
		(3 "B.Mask" user "Board Geometry/Soldermask Bottom")
		(17 "Dwgs.User" user "User.Drawings")
		(19 "Cmts.User" user "User.Comments")
		(21 "Eco1.User" user "User.Eco1")
		(23 "Eco2.User" user "User.Eco2")
		(25 "Edge.Cuts" user "Board Geometry/Outline")
		(27 "Margin" user)
		(31 "F.CrtYd" user "Package Geometry/Place Bound Top")
		(29 "B.CrtYd" user "Package Geometry/Place Bound Bottom")
		(35 "F.Fab" user "Ref Des/Assembly Top")
		(33 "B.Fab" user "Ref Des/Assembly Bottom")
	)
	(footprint ""
		(layer "F.Cu")
		(at 421.284654 -428.285402 -90)
		(property "Reference" "U16"
			(at 1.53289 -3.07594 90)
			(unlocked yes)
			(layer "F.SilkS")
			(effects
				(font
					(size 0.7874 0.5842)
					(thickness 0.1524)
				)
				(justify left)
			)
		)
		(property "Value" ""
			(at 0 0 270)
			(layer "F.Fab")
			(effects
				(font
					(size 1.27 1.27)
				)
			)
		)
		(duplicate_pad_numbers_are_jumpers no)
		(fp_line
			(start -1.8288 2.500122)
			(end 1.8288 2.500122)
			(stroke
				(width 0.1524)
				(type default)
			)
			(layer "F.SilkS")
		)
		(fp_line
			(start 1.8288 2.500122)
			(end 1.8288 -2.500122)
			(stroke
				(width 0.1524)
				(type default)
			)
			(layer "F.SilkS")
		)
		(fp_line
			(start 0 -1.4224)
			(end -1.077722 -2.500122)
			(stroke
				(width 0.1524)
				(type default)
			)
			(layer "F.SilkS")
		)
		(fp_line
			(start -1.8288 -2.500122)
			(end -1.8288 2.500122)
			(stroke
				(width 0.1524)
				(type default)
			)
			(layer "F.SilkS")
		)
		(fp_line
			(start -1.077722 -2.500122)
			(end -1.8288 -2.500122)
			(stroke
				(width 0.1524)
				(type default)
			)
			(layer "F.SilkS")
		)
		(fp_line
			(start 1.077722 -2.500122)
			(end 0 -1.4224)
			(stroke
				(width 0.1524)
				(type default)
			)
			(layer "F.SilkS")
		)
		(fp_line
			(start 1.8288 -2.500122)
			(end 1.077722 -2.500122)
			(stroke
				(width 0.1524)
				(type default)
			)
			(layer "F.SilkS")
		)
		(fp_poly
			(pts
				(xy -4.5085 -2.413) (xy -4.5085 -1.397) (xy -3.4925 -1.905)
			)
			(stroke
				(width 0)
				(type default)
			)
			(fill yes)
			(layer "F.SilkS")
		)
		(fp_line
			(start -1.999996 2.500122)
			(end 1.999996 2.500122)
			(stroke
				(width 0.1)
				(type default)
			)
			(layer "F.Fab")
		)
		(fp_line
			(start 1.999996 2.500122)
			(end 1.999996 -2.500122)
			(stroke
				(width 0.1)
				(type default)
			)
			(layer "F.Fab")
		)
		(fp_line
			(start -1.999996 -2.500122)
			(end -1.999996 2.500122)
			(stroke
				(width 0.1)
				(type default)
			)
			(layer "F.Fab")
		)
		(fp_line
			(start 1.999996 -2.500122)
			(end -1.999996 -2.500122)
			(stroke
				(width 0.1)
				(type default)
			)
			(layer "F.Fab")
		)
		(fp_poly
			(pts
				(xy -4.5085 -2.413) (xy -4.5085 -1.397) (xy -3.4925 -1.905)
			)
			(stroke
				(width 0)
				(type default)
			)
			(fill yes)
			(layer "F.Fab")
		)
		(pad "1" smd rect
			(at -2.599944 -1.905 180)
			(size 0.889 1.27)
			(layers "F.Cu" "F.Mask" "F.Paste")
			(net "Net_10841")
		)
		(pad "2" smd rect
			(at -2.599944 -0.635 180)
			(size 0.889 1.27)
			(layers "F.Cu" "F.Mask" "F.Paste")
			(net "Net_10840")
		)
		(pad "3" smd rect
			(at -2.599944 0.635 180)
			(size 0.889 1.27)
			(layers "F.Cu" "F.Mask" "F.Paste")
			(net "U16_E2")
		)
		(pad "4" smd rect
			(at -2.599944 1.905 180)
			(size 0.889 1.27)
			(layers "F.Cu" "F.Mask" "F.Paste")
			(net "GND")
		)
		(pad "5" smd rect
			(at 2.599944 1.905 180)
			(size 0.889 1.27)
			(layers "F.Cu" "F.Mask" "F.Paste")
			(net "SMB_RT_CPU0_P2_ROM_SDA")
		)
		(pad "6" smd rect
			(at 2.599944 0.635 180)
			(size 0.889 1.27)
			(layers "F.Cu" "F.Mask" "F.Paste")
			(net "SMB_RT_CPU0_P2_ROM_SCL")
		)
		(pad "7" smd rect
			(at 2.599944 -0.635 180)
			(size 0.889 1.27)
			(layers "F.Cu" "F.Mask" "F.Paste")
			(net "GND")
		)
		(pad "8" smd rect
			(at 2.599944 -1.905 180)
			(size 0.889 1.27)
			(layers "F.Cu" "F.Mask" "F.Paste")
			(net "P1V8_CPU0_RT_1D")
		)
	)
	(footprint ""
		(layer "F.Cu")
		(at 304.419 -366.395)
		(property "Reference" "R8071"
			(at 0 0 0)
			(layer "F.SilkS")
			(hide yes)
			(effects
				(font
					(size 1.27 1.27)
				)
			)
		)
		(property "Value" ""
			(at 0 0 0)
			(layer "F.Fab")
			(effects
				(font
					(size 1.27 1.27)
				)
			)
		)
		(duplicate_pad_numbers_are_jumpers no)
		(fp_line
			(start -0.7874 -0.4064)
			(end 0.7874 -0.4064)
			(stroke
				(width 0.1524)
				(type default)
			)
			(layer "F.SilkS")
		)
		(fp_line
			(start -0.7874 0.4064)
			(end -0.7874 -0.4064)
			(stroke
				(width 0.1524)
				(type default)
			)
			(layer "F.SilkS")
		)
		(fp_line
			(start 0.7874 -0.4064)
			(end 0.7874 0.4064)
			(stroke
				(width 0.1524)
				(type default)
			)
			(layer "F.SilkS")
		)
		(fp_line
			(start 0.7874 0.4064)
			(end -0.7874 0.4064)
			(stroke
				(width 0.1524)
				(type default)
			)
			(layer "F.SilkS")
		)
		(fp_line
			(start -0.67945 -0.305054)
			(end -0.12065 -0.305054)
			(stroke
				(width 0.1)
				(type default)
			)
			(layer "F.Fab")
		)
		(fp_line
			(start -0.67945 0.3048)
			(end -0.67945 -0.305054)
			(stroke
				(width 0.1)
				(type default)
			)
			(layer "F.Fab")
		)
		(fp_line
			(start -0.12065 -0.305054)
			(end -0.12065 -0.2794)
			(stroke
				(width 0.1)
				(type default)
			)
			(layer "F.Fab")
		)
		(fp_line
			(start -0.12065 -0.2794)
			(end 0.12065 -0.2794)
			(stroke
				(width 0.1)
				(type default)
			)
			(layer "F.Fab")
		)
		(fp_line
			(start -0.12065 0.2794)
			(end -0.12065 0.3048)
			(stroke
				(width 0.1)
				(type default)
			)
			(layer "F.Fab")
		)
		(fp_line
			(start -0.12065 0.3048)
			(end -0.67945 0.3048)
			(stroke
				(width 0.1)
				(type default)
			)
			(layer "F.Fab")
		)
		(fp_line
			(start 0.120396 0.2794)
			(end -0.12065 0.2794)
			(stroke
				(width 0.1)
				(type default)
			)
			(layer "F.Fab")
		)
		(fp_line
			(start 0.120396 0.3048)
			(end 0.120396 0.2794)
			(stroke
				(width 0.1)
				(type default)
			)
			(layer "F.Fab")
		)
		(fp_line
			(start 0.12065 -0.3048)
			(end 0.67945 -0.3048)
			(stroke
				(width 0.1)
				(type default)
			)
			(layer "F.Fab")
		)
		(fp_line
			(start 0.12065 -0.2794)
			(end 0.12065 -0.3048)
			(stroke
				(width 0.1)
				(type default)
			)
			(layer "F.Fab")
		)
		(fp_line
			(start 0.67945 -0.3048)
			(end 0.67945 0.3048)
			(stroke
				(width 0.1)
				(type default)
			)
			(layer "F.Fab")
		)
		(fp_line
			(start 0.67945 0.3048)
			(end 0.120396 0.3048)
			(stroke
				(width 0.1)
				(type default)
			)
			(layer "F.Fab")
		)
		(pad "1" smd circle
			(at -0.40005 0)
			(size 0 0)
			(layers "F.Cu" "F.Mask" "F.Paste")
			(net "SMB_SCM_2_R5_SCL")
		)
		(pad "2" smd circle
			(at 0.40005 0)
			(size 0 0)
			(layers "F.Cu" "F.Mask" "F.Paste")
			(net "SMB_CLK_PVDDCR_CPU1_P0_R")
		)
	)
)
